FILE_TYPE = CONNECTIVITY;
{Allegro Design Entry HDL 17.4-2019 S026 (4007227) 1/17/2022}
"PAGE_NUMBER" = 386;
0"NC";
1"GND\g";
2"GND\g";
3"GND\g";
4"P1V8_CPU0_RT_1D\g";
5"RT_CPU0_P0_VQPS";
6"P1V8_CPU0_RT0_1A_1D\g";
7"P0V9_CPU0_RT_2D\g";
8"NCF_CPU0_P0_GND";
9"GND\g";
10"P0V9_CPU0_RT0_2A\g";
11"GND\g";
12"NCF_A1_CPU0_P0_GND";
13"P1V8_CPU0_RT0_1A\g";
14"P0V9_CPU0_RT0_2A_2D\g";
%"UNIVERSAL_GND"
"1","(-7400,3100)","0","pure_quanta_power","I1";
;
CDS_LIB"pure_quanta_power"
HDL_POWER"GND";
"A"1;
%"UNIVERSAL_GND"
"1","(-2875,1325)","0","pure_quanta_power","I10";
;
CDS_LIB"pure_quanta_power"
HDL_POWER"GND";
"A"9;
%"P1V0"
"1","(-4400,3800)","0","pure_quanta_power","I11";
;
HDL_POWER"P0V9_CPU0_RT_2D"
CDS_LIB"pure_quanta_power";
"A"7;
%"UNIVERSAL_GND"
"1","(-1200,950)","0","pure_quanta_power","I12";
;
CDS_LIB"pure_quanta_power"
HDL_POWER"GND";
"A"2;
%"Q_RES"
"2","(-1200,1250)","0","pure_quanta","I13";
;
LOCATION"R6821"
$SEC"1"
CDS_SEC"1"
PACK_TYPE"0201LF"
VALUE"0"
TOLERANCE"5%"
WATTAGE"1/20W"
MATERIAL"CHIP"
CDS_LIB"pure_quanta"
PART_NUMBER"CS00001JE10";
"A"
$PN"1"8;
"B"
$PN"2"2;
%"UNIVERSAL_GND"
"1","(-1050,1500)","0","pure_quanta_power","I14";
;
CDS_LIB"pure_quanta_power"
HDL_POWER"GND";
"A"3;
%"Q_RES"
"2","(-1050,1800)","0","pure_quanta","I15";
;
LOCATION"R6820"
$SEC"1"
CDS_SEC"1"
PACK_TYPE"0201LF"
MATERIAL"CHIP"
TOLERANCE"5%"
VALUE"0"
WATTAGE"1/20W"
CDS_LIB"pure_quanta"
PART_NUMBER"CS00001JE10";
"A"
$PN"1"12;
"B"
$PN"2"3;
%"UNIVERSAL_GND"
"1","(-825,2050)","0","pure_quanta_power","I16";
;
CDS_LIB"pure_quanta_power"
HDL_POWER"GND";
"A"11;
%"PT5161LRS"
"5","(-2175,3575)","0","pure_quanta","I17";
;
LOCATION"U6010"
$SEC"5"
CDS_SEC"5"
PART_TYPE"SMLF"
MATERIAL"IC"
VALUE"PT5161LRS"
NEEDS_NO_SIZE"TRUE"
CDS_LMAN_SYM_OUTLINE"-350,2150,300,-2150"
CDS_LIB"pure_quanta"
PART_NUMBER"AJ051610U03";
"GND151"
$PN"V35"11;
"GND150"
$PN"V1"11;
"GND149"
$PN"U34"11;
"GND148"
$PN"U2"11;
"GND147"
$PN"T4"11;
"GND146"
$PN"T32"11;
"GND145"
$PN"T22"11;
"GND144"
$PN"T13"11;
"GND143"
$PN"L35"11;
"GND142"
$PN"L1"11;
"GND141"
$PN"K34"11;
"GND140"
$PN"K2"11;
"GND139"
$PN"J4"11;
"GND138"
$PN"J22"11;
"GND137"
$PN"H31"11;
"GND136"
$PN"H19"11;
"GND135"
$PN"H16"11;
"GND134"
$PN"H12"11;
"GND133"
$PN"FJ19"11;
"GND132"
$PN"FJ12"11;
"GND131"
$PN"FF21"11;
"GND130"
$PN"FF14"11;
"GND129"
$PN"FD35"11;
"GND128"
$PN"FD1"11;
"GND127"
$PN"FC9"11;
"GND126"
$PN"FC6"11;
"GND125"
$PN"FC3"11;
"GND124"
$PN"FC28"11;
"GND123"
$PN"FC25"11;
"GND122"
$PN"FC23"11;
"GND121"
$PN"FC19"11;
"GND120"
$PN"FB34"11;
"GND119"
$PN"FB2"11;
"GND118"
$PN"FA32"11;
"GND117"
$PN"FA15"11;
"GND116"
$PN"ET35"11;
"GND115"
$PN"ET1"11;
"GND114"
$PN"ER34"11;
"GND113"
$PN"ER2"11;
"GND112"
$PN"EP4"11;
"GND111"
$PN"EP32"11;
"GND110"
$PN"EP22"11;
"GND109"
$PN"EP13"11;
"GND108"
$PN"EJ35"11;
"GND107"
$PN"EJ1"11;
"GND106"
$PN"EH34"11;
"GND105"
$PN"EH2"11;
"GND104"
$PN"EG4"11;
"GND103"
$PN"EG32"11;
"GND102"
$PN"EG22"11;
"GND101"
$PN"EG13"11;
"GND100"
$PN"EB35"11;
"GND99"
$PN"EB1"11;
"GND98"
$PN"EA34"11;
"GND97"
$PN"EA2"11;
"GND96"
$PN"E33"11;
"GND95"
$PN"E27"11;
"GND94"
$PN"E14"11;
"GND93"
$PN"DY4"11;
"GND92"
$PN"DY32"11;
"GND91"
$PN"DY22"11;
"GND90"
$PN"DY13"11;
"GND89"
$PN"DR35"11;
"GND88"
$PN"DR1"11;
"GND87"
$PN"DP34"11;
"GND86"
$PN"DP2"11;
"GND85"
$PN"DN4"11;
"GND84"
$PN"DN32"11;
"GND83"
$PN"DN22"11;
"NCF_GND12"
$PN"FH34"8;
"NCF_GND11"
$PN"FH2"8;
"NCF_GND10"
$PN"FG35"8;
"NCF_GND9"
$PN"FG1"8;
"NCF_GND8"
$PN"FE34"8;
"NCF_GND7"
$PN"FE2"8;
"NCF_GND6"
$PN"D35"8;
"NCF_GND5"
$PN"D1"8;
"NCF_GND4"
$PN"C34"8;
"NCF_GND3"
$PN"C2"8;
"NCF_GND2"
$PN"A35"8;
"NCF_GND1"
$PN"A1"12;
"GND82"
$PN"DN13"9;
"GND81"
$PN"DH35"9;
"GND80"
$PN"DH1"9;
"GND79"
$PN"DG34"9;
"GND78"
$PN"DG2"9;
"GND77"
$PN"DF4"9;
"GND76"
$PN"DF32"9;
"GND75"
$PN"DF22"9;
"GND74"
$PN"DF13"9;
"GND73"
$PN"DA35"9;
"GND72"
$PN"DA1"9;
"GND71"
$PN"CY34"9;
"GND70"
$PN"CY2"9;
"GND69"
$PN"CW4"9;
"GND68"
$PN"CW32"9;
"GND67"
$PN"CW22"9;
"GND66"
$PN"CW13"9;
"GND65"
$PN"CP35"9;
"GND64"
$PN"CP1"9;
"GND63"
$PN"CN34"9;
"GND62"
$PN"CN2"9;
"GND61"
$PN"CM4"9;
"GND60"
$PN"CM32"9;
"GND59"
$PN"CM22"9;
"GND58"
$PN"CM13"9;
"GND57"
$PN"CG35"9;
"GND56"
$PN"CG1"9;
"GND55"
$PN"CF34"9;
"GND54"
$PN"CF2"9;
"GND53"
$PN"CE4"9;
"GND52"
$PN"CE32"9;
"GND51"
$PN"CE22"9;
"GND50"
$PN"CE13"9;
"GND49"
$PN"BY35"9;
"GND48"
$PN"BY1"9;
"GND47"
$PN"BW34"9;
"GND46"
$PN"BW2"9;
"GND45"
$PN"BV4"9;
"GND44"
$PN"BV32"9;
"GND43"
$PN"BV22"9;
"GND42"
$PN"BV13"9;
"GND41"
$PN"BN35"9;
"GND40"
$PN"BN1"9;
"GND39"
$PN"BM34"9;
"GND38"
$PN"BM2"9;
"GND37"
$PN"BL4"9;
"GND36"
$PN"BL32"9;
"GND35"
$PN"BL22"9;
"GND34"
$PN"BL13"9;
"GND33"
$PN"BF35"9;
"GND32"
$PN"BF1"9;
"GND31"
$PN"BE34"9;
"GND30"
$PN"BE2"9;
"GND29"
$PN"BD4"9;
"GND28"
$PN"BD32"9;
"GND27"
$PN"BD22"9;
"GND26"
$PN"BD13"9;
"GND25"
$PN"B19"9;
"GND24"
$PN"AW35"9;
"GND23"
$PN"AW1"9;
"GND22"
$PN"AV34"9;
"GND21"
$PN"AV2"9;
"GND20"
$PN"AU4"9;
"GND19"
$PN"AU32"9;
"GND18"
$PN"AU22"9;
"GND17"
$PN"AU13"9;
"GND16"
$PN"AM35"9;
"GND15"
$PN"AM1"9;
"GND14"
$PN"AL34"9;
"GND13"
$PN"AL2"9;
"GND12"
$PN"AK4"9;
"GND11"
$PN"AK32"9;
"GND10"
$PN"AK22"9;
"GND9"
$PN"AK13"9;
"GND8"
$PN"AE35"9;
"GND7"
$PN"AE1"9;
"GND6"
$PN"AD34"9;
"GND5"
$PN"AD2"9;
"GND4"
$PN"AC4"9;
"GND3"
$PN"AC32"9;
"GND2"
$PN"AC22"9;
"GND1"
$PN"AC13"9;
%"Q_RES"
"2","(-7400,3350)","0","pure_quanta","I18";
;
LOCATION"R6809"
$SEC"1"
CDS_SEC"1"
MATERIAL"CHIP"
PACK_TYPE"0201LF"
WATTAGE"1/20W"
VALUE"200"
TOLERANCE"1%"
CDS_LIB"pure_quanta"
PART_NUMBER"CS12001FE12";
"A"
$PN"1"5;
"B"
$PN"2"1;
%"Q_RES"
"2","(-8425,3900)","0","pure_quanta","I19";
;
LOCATION"R6808"
$SEC"1"
CDS_SEC"1"
PACK_TYPE"0201LF"
TOLERANCE"1%"
VALUE"1K"
WATTAGE"1/20W"
MATERIAL"EMPTY"
CDS_LIB"pure_quanta"
PART_NUMBER"CS21001FE07";
"A"
$PN"1"4;
"B"
$PN"2"5;
%"PT5161LRS"
"4","(-6250,4150)","0","pure_quanta","I3";
;
LOCATION"U6010"
$SEC"4"
CDS_SEC"4"
PART_TYPE"SMLF"
VALUE"PT5161LRS"
MATERIAL"IC"
NEEDS_NO_SIZE"TRUE"
CDS_LMAN_SYM_OUTLINE"-450,750,400,-750"
CDS_LIB"pure_quanta"
PART_NUMBER"AJ051610U03";
"PWR_2A_20"
$PN"T20"10;
"PWR_2A_19"
$PN"T17"10;
"PWR_2A_18"
$PN"EP20"10;
"PWR_2A_17"
$PN"EP17"10;
"PWR_2A_16"
$PN"EG20"10;
"PWR_2A_15"
$PN"EG17"10;
"PWR_2A_14"
$PN"DY20"10;
"PWR_2A_13"
$PN"DY17"10;
"PWR_2A_12"
$PN"DN20"10;
"PWR_2A_11"
$PN"DN17"10;
"PWR_2A_10"
$PN"DF20"14;
"PWR_2A_9"
$PN"DF17"14;
"PWR_2A_8"
$PN"BD20"14;
"PWR_2A_7"
$PN"BD17"14;
"PWR_2A_6"
$PN"AU20"10;
"PWR_2A_5"
$PN"AU17"10;
"PWR_2A_4"
$PN"AK20"10;
"PWR_2A_3"
$PN"AK17"10;
"PWR_2A_2"
$PN"AC20"10;
"PWR_2A_1"
$PN"AC17"10;
"PWR_1D"
$PN"BV17"6;
"PWR_2D_4"
$PN"CW20"7;
"PWR_2D_3"
$PN"CW17"7;
"PWR_2D_2"
$PN"BL20"7;
"PWR_2D_1"
$PN"BL17"7;
"PWR_1A_5"
$PN"CM20"13;
"PWR_1A_4"
$PN"CM17"13;
"PWR_1A_3"
$PN"CE20"13;
"PWR_1A_2"
$PN"CE17"13;
"PWR_1A_1"
$PN"BV20"13;
"VQPS"
$PN"G1"5;
%"P1V0"
"1","(-8425,4125)","0","pure_quanta_power","I5";
;
HDL_POWER"P1V8_CPU0_RT_1D"
CDS_LIB"pure_quanta_power";
"A"4;
%"P1V0"
"1","(-8100,4400)","0","pure_quanta_power","I6";
;
HDL_POWER"P1V8_CPU0_RT0_1A_1D"
CDS_LIB"pure_quanta_power";
"A"6;
%"P1V0"
"1","(-7525,4850)","0","pure_quanta_power","I7";
;
HDL_POWER"P1V8_CPU0_RT0_1A"
CDS_LIB"pure_quanta_power";
"A"13;
%"VCC_CORE"
"1","(-5000,4550)","0","pure_quanta_power","I8";
;
HDL_POWER"P0V9_CPU0_RT0_2A_2D"
CDS_LIB"pure_quanta_power";
"A"14;
%"VCC_CORE"
"1","(-4425,5025)","0","pure_quanta_power","I9";
;
HDL_POWER"P0V9_CPU0_RT0_2A"
CDS_LIB"pure_quanta_power";
"A"10;
END.
